# T6G (Grand Teton) — schematic netlist excerpt (pin names and nets, part order shuffled) for the footprints in the layout excerpt that follows; sources: Cadence DE-HDL packaged netlist, KiCad conversion of 04192023_DAF0TMB3IC0_F0TG_MB_C_brd_V02_OCP.brd

C1097  Q_CAP  0.1UF 25V 10% X7R  pkg 0402  page 357 : A = P3V3_AUX ; B = GND
R276  Q_RES  4.7K 5% CHIP  pkg 0402LF  page 28 : A = CPU0_PWR_GOOD ; B = PVDD18_S5_P0

(kicad_pcb
	(version 20260206)
	(generator "pcbnew")
	(generator_version "10.0")
	(general
		(thickness 1.6)
		(legacy_teardrops no)
	)
	(paper "A4")
	(title_block
		(title "04192023_DAF0TMB3IC0_F0TG_MB_C_brd_V02_OCP.brd")
		(comment 1 "Grand Teton / footprints 1967-1968 of 8354")
	)
	(layers
		(0 "F.Cu" signal "TOP")
		(4 "In1.Cu" signal "GND")
		(6 "In2.Cu" signal "IN1")
		(8 "In3.Cu" signal "GND1")
		(10 "In4.Cu" signal "IN2")
		(12 "In5.Cu" signal "GND2")
		(14 "In6.Cu" signal "IN3")
		(16 "In7.Cu" signal "GND3")
		(18 "In8.Cu" signal "VCC")
		(20 "In9.Cu" signal "VCC1")
		(22 "In10.Cu" signal "GND4")
		(24 "In11.Cu" signal "IN4")
		(26 "In12.Cu" signal "GND5")
		(28 "In13.Cu" signal "IN5")
		(30 "In14.Cu" signal "GND6")
		(32 "In15.Cu" signal "IN6")
		(34 "In16.Cu" signal "GND7")
		(2 "B.Cu" signal "BOTTOM")
		(9 "F.Adhes" user "F.Adhesive")
		(11 "B.Adhes" user "B.Adhesive")
		(13 "F.Paste" user "Package Geometry/Pastemask Top")
		(15 "B.Paste" user "Package Geometry/Pastemask Bottom")
		(5 "F.SilkS" user "Ref Des/Silkscreen Top")
		(7 "B.SilkS" user "Ref Des/Silkscreen Bottom")
		(1 "F.Mask" user "Board Geometry/Soldermask Top")
		(3 "B.Mask" user "Board Geometry/Soldermask Bottom")
		(17 "Dwgs.User" user "User.Drawings")
		(19 "Cmts.User" user "User.Comments")
		(21 "Eco1.User" user "User.Eco1")
		(23 "Eco2.User" user "User.Eco2")
		(25 "Edge.Cuts" user "Board Geometry/Outline")
		(27 "Margin" user)
		(31 "F.CrtYd" user "Package Geometry/Place Bound Top")
		(29 "B.CrtYd" user "Package Geometry/Place Bound Bottom")
		(35 "F.Fab" user "Ref Des/Assembly Top")
		(33 "B.Fab" user "Ref Des/Assembly Bottom")
	)
	(footprint ""
		(layer "F.Cu")
		(at 398.276318 -75.518264)
		(property "Reference" "C1097"
			(at 0 0 0)
			(layer "F.SilkS")
			(hide yes)
			(effects
				(font
					(size 1.27 1.27)
				)
			)
		)
		(property "Value" ""
			(at 0 0 0)
			(layer "F.Fab")
			(effects
				(font
					(size 1.27 1.27)
				)
			)
		)
		(duplicate_pad_numbers_are_jumpers no)
		(fp_line
			(start -0.7874 -0.4064)
			(end 0.7874 -0.4064)
			(stroke
				(width 0.1524)
				(type default)
			)
			(layer "F.SilkS")
		)
		(fp_line
			(start -0.7874 0.4064)
			(end -0.7874 -0.4064)
			(stroke
				(width 0.1524)
				(type default)
			)
			(layer "F.SilkS")
		)
		(fp_line
			(start 0.7874 -0.4064)
			(end 0.7874 0.4064)
			(stroke
				(width 0.1524)
				(type default)
			)
			(layer "F.SilkS")
		)
		(fp_line
			(start 0.7874 0.4064)
			(end -0.7874 0.4064)
			(stroke
				(width 0.1524)
				(type default)
			)
			(layer "F.SilkS")
		)
		(fp_line
			(start -0.67945 -0.305054)
			(end -0.12065 -0.305054)
			(stroke
				(width 0.1)
				(type default)
			)
			(layer "F.Fab")
		)
		(fp_line
			(start -0.67945 0.3048)
			(end -0.67945 -0.305054)
			(stroke
				(width 0.1)
				(type default)
			)
			(layer "F.Fab")
		)
		(fp_line
			(start -0.12065 -0.305054)
			(end -0.12065 -0.2794)
			(stroke
				(width 0.1)
				(type default)
			)
			(layer "F.Fab")
		)
		(fp_line
			(start -0.12065 -0.2794)
			(end 0.12065 -0.2794)
			(stroke
				(width 0.1)
				(type default)
			)
			(layer "F.Fab")
		)
		(fp_line
			(start -0.12065 0.2794)
			(end -0.12065 0.3048)
			(stroke
				(width 0.1)
				(type default)
			)
			(layer "F.Fab")
		)
		(fp_line
			(start -0.12065 0.3048)
			(end -0.67945 0.3048)
			(stroke
				(width 0.1)
				(type default)
			)
			(layer "F.Fab")
		)
		(fp_line
			(start 0.120396 0.2794)
			(end -0.12065 0.2794)
			(stroke
				(width 0.1)
				(type default)
			)
			(layer "F.Fab")
		)
		(fp_line
			(start 0.120396 0.3048)
			(end 0.120396 0.2794)
			(stroke
				(width 0.1)
				(type default)
			)
			(layer "F.Fab")
		)
		(fp_line
			(start 0.12065 -0.3048)
			(end 0.67945 -0.3048)
			(stroke
				(width 0.1)
				(type default)
			)
			(layer "F.Fab")
		)
		(fp_line
			(start 0.12065 -0.2794)
			(end 0.12065 -0.3048)
			(stroke
				(width 0.1)
				(type default)
			)
			(layer "F.Fab")
		)
		(fp_line
			(start 0.67945 -0.3048)
			(end 0.67945 0.3048)
			(stroke
				(width 0.1)
				(type default)
			)
			(layer "F.Fab")
		)
		(fp_line
			(start 0.67945 0.3048)
			(end 0.120396 0.3048)
			(stroke
				(width 0.1)
				(type default)
			)
			(layer "F.Fab")
		)
		(pad "1" smd circle
			(at -0.40005 0)
			(size 0 0)
			(layers "F.Cu" "F.Mask" "F.Paste")
			(net "P3V3_AUX")
		)
		(pad "2" smd circle
			(at 0.40005 0)
			(size 0 0)
			(layers "F.Cu" "F.Mask" "F.Paste")
			(net "GND")
		)
	)
	(footprint ""
		(layer "F.Cu")
		(at 402.126958 -321.002152 90)
		(property "Reference" "R276"
			(at 0 0 90)
			(layer "F.SilkS")
			(hide yes)
			(effects
				(font
					(size 1.27 1.27)
				)
			)
		)
		(property "Value" ""
			(at 0 0 90)
			(layer "F.Fab")
			(effects
				(font
					(size 1.27 1.27)
				)
			)
		)
		(duplicate_pad_numbers_are_jumpers no)
		(fp_line
			(start 0.7874 -0.4064)
			(end 0.7874 0.4064)
			(stroke
				(width 0.1524)
				(type default)
			)
			(layer "F.SilkS")
		)
		(fp_line
			(start -0.7874 -0.4064)
			(end 0.7874 -0.4064)
			(stroke
				(width 0.1524)
				(type default)
			)
			(layer "F.SilkS")
		)
		(fp_line
			(start 0.7874 0.4064)
			(end -0.7874 0.4064)
			(stroke
				(width 0.1524)
				(type default)
			)
			(layer "F.SilkS")
		)
		(fp_line
			(start -0.7874 0.4064)
			(end -0.7874 -0.4064)
			(stroke
				(width 0.1524)
				(type default)
			)
			(layer "F.SilkS")
		)
		(fp_line
			(start -0.12065 -0.305054)
			(end -0.12065 -0.2794)
			(stroke
				(width 0.1)
				(type default)
			)
			(layer "F.Fab")
		)
		(fp_line
			(start -0.67945 -0.305054)
			(end -0.12065 -0.305054)
			(stroke
				(width 0.1)
				(type default)
			)
			(layer "F.Fab")
		)
		(fp_line
			(start 0.67945 -0.3048)
			(end 0.67945 0.3048)
			(stroke
				(width 0.1)
				(type default)
			)
			(layer "F.Fab")
		)
		(fp_line
			(start 0.12065 -0.3048)
			(end 0.67945 -0.3048)
			(stroke
				(width 0.1)
				(type default)
			)
			(layer "F.Fab")
		)
		(fp_line
			(start 0.12065 -0.2794)
			(end 0.12065 -0.3048)
			(stroke
				(width 0.1)
				(type default)
			)
			(layer "F.Fab")
		)
		(fp_line
			(start -0.12065 -0.2794)
			(end 0.12065 -0.2794)
			(stroke
				(width 0.1)
				(type default)
			)
			(layer "F.Fab")
		)
		(fp_line
			(start 0.120396 0.2794)
			(end -0.12065 0.2794)
			(stroke
				(width 0.1)
				(type default)
			)
			(layer "F.Fab")
		)
		(fp_line
			(start -0.12065 0.2794)
			(end -0.12065 0.3048)
			(stroke
				(width 0.1)
				(type default)
			)
			(layer "F.Fab")
		)
		(fp_line
			(start 0.67945 0.3048)
			(end 0.120396 0.3048)
			(stroke
				(width 0.1)
				(type default)
			)
			(layer "F.Fab")
		)
		(fp_line
			(start 0.120396 0.3048)
			(end 0.120396 0.2794)
			(stroke
				(width 0.1)
				(type default)
			)
			(layer "F.Fab")
		)
		(fp_line
			(start -0.12065 0.3048)
			(end -0.67945 0.3048)
			(stroke
				(width 0.1)
				(type default)
			)
			(layer "F.Fab")
		)
		(fp_line
			(start -0.67945 0.3048)
			(end -0.67945 -0.305054)
			(stroke
				(width 0.1)
				(type default)
			)
			(layer "F.Fab")
		)
		(pad "1" smd circle
			(at -0.40005 0 90)
			(size 0 0)
			(layers "F.Cu" "F.Mask" "F.Paste")
			(net "CPU0_PWR_GOOD")
		)
		(pad "2" smd circle
			(at 0.40005 0 90)
			(size 0 0)
			(layers "F.Cu" "F.Mask" "F.Paste")
			(net "PVDD18_S5_P0")
		)
	)
)
